FILE_TYPE = CONNECTIVITY;
{Allegro Design Entry HDL 17.4-2019 S026 (4007227) 1/17/2022}
"PAGE_NUMBER" = 50;
0"NC";
1"GMI_CPU1_G2_CPU0_G0_TX_DN<15:0>";
2"GMI_CPU1_G2_CPU0_G0_TX_DP<15:0>";
3"GMI_CPU1_G3_CPU0_G1_TX_DN<15:0>";
4"GMI_CPU1_G3_CPU0_G1_TX_DP<15:0>";
5"GMI_CPU0_G0_CPU1_G2_TX_DP<15:0>";
6"GMI_CPU0_G0_CPU1_G2_TX_DN<15:0>";
7"GMI_CPU0_G1_CPU1_G3_TX_DN<15:0>";
8"GMI_CPU0_G1_CPU1_G3_TX_DP<15:0>";
9"GMI_CPU0_G1_CPU1_G3_TX_DN<13>";
10"GMI_CPU0_G1_CPU1_G3_TX_DN<3>";
11"GMI_CPU0_G1_CPU1_G3_TX_DN<0>";
12"GMI_CPU0_G1_CPU1_G3_TX_DN<6>";
13"GMI_CPU0_G1_CPU1_G3_TX_DP<13>";
14"GMI_CPU0_G1_CPU1_G3_TX_DP<10>";
15"GMI_CPU0_G1_CPU1_G3_TX_DP<1>";
16"GMI_CPU0_G1_CPU1_G3_TX_DP<4>";
17"GMI_CPU0_G1_CPU1_G3_TX_DN<14>";
18"GMI_CPU0_G1_CPU1_G3_TX_DN<11>";
19"GMI_CPU0_G1_CPU1_G3_TX_DN<8>";
20"GMI_CPU0_G1_CPU1_G3_TX_DP<6>";
21"GMI_CPU0_G1_CPU1_G3_TX_DN<4>";
22"GMI_CPU0_G1_CPU1_G3_TX_DN<1>";
23"GMI_CPU0_G1_CPU1_G3_TX_DP<8>";
24"GMI_CPU0_G1_CPU1_G3_TX_DN<7>";
25"GMI_CPU0_G1_CPU1_G3_TX_DP<14>";
26"GMI_CPU0_G1_CPU1_G3_TX_DP<11>";
27"GMI_CPU0_G1_CPU1_G3_TX_DP<5>";
28"GMI_CPU0_G1_CPU1_G3_TX_DP<2>";
29"GMI_CPU0_G1_CPU1_G3_TX_DN<9>";
30"GMI_CPU0_G1_CPU1_G3_TX_DN<15>";
31"GMI_CPU0_G1_CPU1_G3_TX_DN<12>";
32"GMI_CPU0_G1_CPU1_G3_TX_DP<7>";
33"GMI_CPU0_G1_CPU1_G3_TX_DN<2>";
34"GMI_CPU0_G1_CPU1_G3_TX_DN<5>";
35"GMI_CPU0_G1_CPU1_G3_TX_DP<12>";
36"GMI_CPU0_G1_CPU1_G3_TX_DP<9>";
37"GMI_CPU0_G1_CPU1_G3_TX_DP<0>";
38"GMI_CPU0_G1_CPU1_G3_TX_DP<15>";
39"GMI_CPU0_G1_CPU1_G3_TX_DP<3>";
40"GMI_CPU0_G1_CPU1_G3_TX_DN<10>";
41"GMI_CPU0_G0_CPU1_G2_TX_DN<8>";
42"GMI_CPU0_G0_CPU1_G2_TX_DN<9>";
43"GMI_CPU0_G0_CPU1_G2_TX_DN<10>";
44"GMI_CPU0_G0_CPU1_G2_TX_DP<8>";
45"GMI_CPU0_G0_CPU1_G2_TX_DN<11>";
46"GMI_CPU0_G0_CPU1_G2_TX_DP<9>";
47"GMI_CPU0_G0_CPU1_G2_TX_DN<12>";
48"GMI_CPU0_G0_CPU1_G2_TX_DP<10>";
49"GMI_CPU0_G0_CPU1_G2_TX_DN<13>";
50"GMI_CPU0_G0_CPU1_G2_TX_DP<11>";
51"GMI_CPU0_G0_CPU1_G2_TX_DN<14>";
52"GMI_CPU0_G0_CPU1_G2_TX_DP<12>";
53"GMI_CPU0_G0_CPU1_G2_TX_DN<15>";
54"GMI_CPU0_G0_CPU1_G2_TX_DP<13>";
55"GMI_CPU0_G0_CPU1_G2_TX_DP<14>";
56"GMI_CPU0_G0_CPU1_G2_TX_DP<15>";
57"GMI_CPU0_G0_CPU1_G2_TX_DN<0>";
58"GMI_CPU0_G0_CPU1_G2_TX_DP<0>";
59"GMI_CPU0_G0_CPU1_G2_TX_DN<2>";
60"GMI_CPU0_G0_CPU1_G2_TX_DP<2>";
61"GMI_CPU0_G0_CPU1_G2_TX_DN<4>";
62"GMI_CPU0_G0_CPU1_G2_TX_DP<4>";
63"GMI_CPU0_G0_CPU1_G2_TX_DN<6>";
64"GMI_CPU0_G0_CPU1_G2_TX_DP<6>";
65"GMI_CPU0_G0_CPU1_G2_TX_DN<1>";
66"GMI_CPU0_G0_CPU1_G2_TX_DP<1>";
67"GMI_CPU0_G0_CPU1_G2_TX_DN<3>";
68"GMI_CPU0_G0_CPU1_G2_TX_DP<3>";
69"GMI_CPU0_G0_CPU1_G2_TX_DN<5>";
70"GMI_CPU0_G0_CPU1_G2_TX_DP<5>";
71"GMI_CPU0_G0_CPU1_G2_TX_DN<7>";
72"GMI_CPU0_G0_CPU1_G2_TX_DP<7>";
73"GMI_CPU1_G3_CPU0_G1_TX_DP<0>";
74"GMI_CPU1_G3_CPU0_G1_TX_DP<3>";
75"GMI_CPU1_G3_CPU0_G1_TX_DP<1>";
76"GMI_CPU1_G3_CPU0_G1_TX_DP<4>";
77"GMI_CPU1_G3_CPU0_G1_TX_DP<2>";
78"GMI_CPU1_G3_CPU0_G1_TX_DN<2>";
79"GMI_CPU1_G3_CPU0_G1_TX_DN<3>";
80"GMI_CPU1_G3_CPU0_G1_TX_DN<0>";
81"GMI_CPU1_G3_CPU0_G1_TX_DN<4>";
82"GMI_CPU1_G3_CPU0_G1_TX_DN<1>";
83"GMI_CPU1_G3_CPU0_G1_TX_DP<6>";
84"GMI_CPU1_G3_CPU0_G1_TX_DP<8>";
85"GMI_CPU1_G3_CPU0_G1_TX_DP<7>";
86"GMI_CPU1_G3_CPU0_G1_TX_DP<9>";
87"GMI_CPU1_G3_CPU0_G1_TX_DP<5>";
88"GMI_CPU1_G3_CPU0_G1_TX_DP<10>";
89"GMI_CPU1_G3_CPU0_G1_TX_DP<13>";
90"GMI_CPU1_G3_CPU0_G1_TX_DP<14>";
91"GMI_CPU1_G3_CPU0_G1_TX_DP<11>";
92"GMI_CPU1_G3_CPU0_G1_TX_DP<12>";
93"GMI_CPU1_G3_CPU0_G1_TX_DP<15>";
94"GMI_CPU1_G3_CPU0_G1_TX_DN<6>";
95"GMI_CPU1_G3_CPU0_G1_TX_DN<11>";
96"GMI_CPU1_G3_CPU0_G1_TX_DN<8>";
97"GMI_CPU1_G3_CPU0_G1_TX_DN<5>";
98"GMI_CPU1_G3_CPU0_G1_TX_DN<14>";
99"GMI_CPU1_G3_CPU0_G1_TX_DN<7>";
100"GMI_CPU1_G3_CPU0_G1_TX_DN<12>";
101"GMI_CPU1_G3_CPU0_G1_TX_DN<9>";
102"GMI_CPU1_G3_CPU0_G1_TX_DN<15>";
103"GMI_CPU1_G3_CPU0_G1_TX_DN<10>";
104"GMI_CPU1_G3_CPU0_G1_TX_DN<13>";
105"GMI_CPU1_G2_CPU0_G0_TX_DP<0>";
106"GMI_CPU1_G2_CPU0_G0_TX_DP<2>";
107"GMI_CPU1_G2_CPU0_G0_TX_DP<1>";
108"GMI_CPU1_G2_CPU0_G0_TX_DP<3>";
109"GMI_CPU1_G2_CPU0_G0_TX_DP<8>";
110"GMI_CPU1_G2_CPU0_G0_TX_DP<4>";
111"GMI_CPU1_G2_CPU0_G0_TX_DP<6>";
112"GMI_CPU1_G2_CPU0_G0_TX_DP<5>";
113"GMI_CPU1_G2_CPU0_G0_TX_DP<7>";
114"GMI_CPU1_G2_CPU0_G0_TX_DP<9>";
115"GMI_CPU1_G2_CPU0_G0_TX_DP<10>";
116"GMI_CPU1_G2_CPU0_G0_TX_DP<11>";
117"GMI_CPU1_G2_CPU0_G0_TX_DP<12>";
118"GMI_CPU1_G2_CPU0_G0_TX_DP<13>";
119"GMI_CPU1_G2_CPU0_G0_TX_DP<15>";
120"GMI_CPU1_G2_CPU0_G0_TX_DP<14>";
121"GMI_CPU1_G2_CPU0_G0_TX_DN<8>";
122"GMI_CPU1_G2_CPU0_G0_TX_DN<9>";
123"GMI_CPU1_G2_CPU0_G0_TX_DN<10>";
124"GMI_CPU1_G2_CPU0_G0_TX_DN<11>";
125"GMI_CPU1_G2_CPU0_G0_TX_DN<12>";
126"GMI_CPU1_G2_CPU0_G0_TX_DN<13>";
127"GMI_CPU1_G2_CPU0_G0_TX_DN<14>";
128"GMI_CPU1_G2_CPU0_G0_TX_DN<15>";
129"GMI_CPU1_G2_CPU0_G0_TX_DN<0>";
130"GMI_CPU1_G2_CPU0_G0_TX_DN<2>";
131"GMI_CPU1_G2_CPU0_G0_TX_DN<4>";
132"GMI_CPU1_G2_CPU0_G0_TX_DN<6>";
133"GMI_CPU1_G2_CPU0_G0_TX_DN<1>";
134"GMI_CPU1_G2_CPU0_G0_TX_DN<3>";
135"GMI_CPU1_G2_CPU0_G0_TX_DN<5>";
136"GMI_CPU1_G2_CPU0_G0_TX_DN<7>";
%"GENOA_SP5"
"13","(-4750,5050)","0","pure_quanta","I143";
;
LOCATION"U26"
$SEC"13"
CDS_SEC"13"
PART_TYPE"SMLF"
MATERIAL"IO"
VALUE"SOCKET6096_13568-001"
CDS_LIB"pure_quanta"
NEEDS_NO_SIZE"TRUE"
CDS_LMAN_SYM_OUTLINE"-1100,950,1100,-950"
PART_NUMBER"DGA^6000030";
"G2_TXP0"
$PN"N23"119;
"G2_RXN7"
$PN"AC29"41;
"G2_RXN6"
$PN"AE29"42;
"G2_RXN5"
$PN"AG26"43;
"G2_RXP7"
$PN"AC30"44;
"G2_TXN7"
$PN"J30"121;
"G2_RXN4"
$PN"AC26"45;
"G2_RXP6"
$PN"AE30"46;
"G2_TXN6"
$PN"L27"122;
"G2_RXN3"
$PN"AE26"47;
"G2_RXP5"
$PN"AG27"48;
"G2_TXN5"
$PN"G27"123;
"G2_TXP7"
$PN"J29"109;
"G2_RXN2"
$PN"AG23"49;
"G2_RXP4"
$PN"AC27"50;
"G2_TXN4"
$PN"J27"124;
"G2_TXP6"
$PN"L26"114;
"G2_RXN1"
$PN"AC23"51;
"G2_RXP3"
$PN"AE27"52;
"G2_TXN3"
$PN"L24"125;
"G2_TXP5"
$PN"G26"115;
"G2_RXN0"
$PN"AE23"53;
"G2_RXP2"
$PN"AG24"54;
"G2_TXN2"
$PN"G24"126;
"G2_TXP4"
$PN"J26"116;
"G2_RXP1"
$PN"AC24"55;
"G2_TXN1"
$PN"J24"127;
"G2_TXP3"
$PN"L23"117;
"G2_RXP0"
$PN"AE24"56;
"G2_TXN0"
$PN"N24"128;
"G2_TXP2"
$PN"G23"118;
"G2_TXP1"
$PN"J23"120;
"G2_RXN15"
$PN"AF35"57;
"G2_RXP15"
$PN"AF36"58;
"G2_RXN13"
$PN"AB35"59;
"G2_RXP13"
$PN"AB36"60;
"G2_RXN11"
$PN"AA32"61;
"G2_RXP11"
$PN"AA33"62;
"G2_RXN9"
$PN"AE32"63;
"G2_RXP9"
$PN"AE33"64;
"G2_RXN14"
$PN"AD35"65;
"G2_RXP14"
$PN"AD36"66;
"G2_RXN12"
$PN"AG32"67;
"G2_RXP12"
$PN"AG33"68;
"G2_RXN10"
$PN"AC32"69;
"G2_RXP10"
$PN"AC33"70;
"G2_RXN8"
$PN"AG29"71;
"G2_RXP8"
$PN"AG30"72;
"G2_TXN15"
$PN"M36"129;
"G2_TXP15"
$PN"M35"105;
"G2_TXN13"
$PN"H36"130;
"G2_TXP13"
$PN"H35"106;
"G2_TXN11"
$PN"G33"131;
"G2_TXP11"
$PN"G32"110;
"G2_TXN9"
$PN"L30"132;
"G2_TXP9"
$PN"L29"111;
"G2_TXN14"
$PN"K36"133;
"G2_TXP14"
$PN"K35"107;
"G2_TXN12"
$PN"L33"134;
"G2_TXP12"
$PN"L32"108;
"G2_TXN10"
$PN"J33"135;
"G2_TXP10"
$PN"J32"112;
"G2_TXN8"
$PN"G30"136;
"G2_TXP8"
$PN"G29"113;
%"GENOA_SP5"
"14","(-4725,2375)","0","pure_quanta","I144";
;
LOCATION"U26"
$SEC"14"
CDS_SEC"14"
PART_TYPE"SMLF"
MATERIAL"IO"
VALUE"SOCKET6096_13568-001"
CDS_LIB"pure_quanta"
NEEDS_NO_SIZE"TRUE"
CDS_LMAN_SYM_OUTLINE"-1100,950,1100,-950"
PART_NUMBER"DGA^6000030";
"G3_RXN2||SATA22_RXN"
$PN"AN23"9;
"G3_TXN9||SATA31_TXN"
$PN"U30"94;
"G3_RXN12||SATA34_RXN"
$PN"AK35"10;
"G3_RXN15||SATA37_RXN"
$PN"AP35"11;
"G3_TXP5||SATA25_TXP"
$PN"N26"88;
"G3_RXN9||SATA31_RXN"
$PN"AL32"12;
"G3_TXP2||SATA22_TXP"
$PN"W23"89;
"G3_RXP2||SATA22_RXP"
$PN"AN24"13;
"G3_RXP5||SATA25_RXP"
$PN"AN27"14;
"G3_RXP14||SATA36_RXP"
$PN"AM36"15;
"G3_TXN4||SATA24_TXN"
$PN"R27"95;
"G3_TXN7||SATA27_TXN"
$PN"R30"96;
"G3_TXN10||SATA32_TXN"
$PN"R33"97;
"G3_TXN13||SATA35_TXN"
$PN"P36"78;
"G3_RXP11||SATA33_RXP"
$PN"AN33"16;
"G3_TXN1||SATA21_TXN"
$PN"R24"98;
"G3_TXP9||SATA31_TXP"
$PN"U29"83;
"G3_TXP15||SATA37_TXP"
$PN"V35"73;
"G3_RXN1||SATA21_RXN"
$PN"AJ23"17;
"G3_RXN4||SATA24_RXN"
$PN"AJ26"18;
"G3_RXN7||SATA27_RXN"
$PN"AJ29"19;
"G3_TXP12||SATA34_TXP"
$PN"U32"74;
"G3_RXP9||SATA31_RXP"
$PN"AL33"20;
"G3_TXP7||SATA27_TXP"
$PN"R29"84;
"G3_TXN8||SATA30_TXN"
$PN"N30"99;
"G3_RXN11||SATA33_RXN"
$PN"AN32"21;
"G3_RXN14||SATA36_RXN"
$PN"AM35"22;
"G3_TXP1||SATA21_TXP"
$PN"R23"90;
"G3_TXP4||SATA24_TXP"
$PN"R26"91;
"G3_RXP7||SATA27_RXP"
$PN"AJ30"23;
"G3_RXN8||SATA30_RXN"
$PN"AN29"24;
"G3_TXN12||SATA34_TXN"
$PN"U33"79;
"G3_TXN15||SATA37_TXN"
$PN"V36"80;
"G3_RXP1||SATA21_RXP"
$PN"AJ24"25;
"G3_RXP4||SATA24_RXP"
$PN"AJ27"26;
"G3_RXP10||SATA32_RXP"
$PN"AJ33"27;
"G3_RXP13||SATA35_RXP"
$PN"AH36"28;
"G3_TXN3||SATA23_TXN"
$PN"U27"100;
"G3_TXN6||SATA26_TXN"
$PN"W27"101;
"G3_RXN6||SATA26_RXN"
$PN"AL29"29;
"G3_TXN0||SATA20_TXN"
$PN"U24"102;
"G3_TXP8||SATA30_TXP"
$PN"N29"85;
"G3_TXP14||SATA36_TXP"
$PN"T35"75;
"G3_RXN0||SATA20_RXN"
$PN"AL23"30;
"G3_RXN3||SATA23_RXN"
$PN"AL26"31;
"G3_RXP8||SATA30_RXP"
$PN"AN30"32;
"G3_TXP11||SATA33_TXP"
$PN"N32"76;
"G3_RXN13||SATA35_RXN"
$PN"AH35"33;
"G3_TXP6||SATA26_TXP"
$PN"W26"86;
"G3_RXN10||SATA32_RXN"
$PN"AJ32"34;
"G3_TXP0||SATA20_TXP"
$PN"U23"93;
"G3_TXP3||SATA23_TXP"
$PN"U26"92;
"G3_RXP3||SATA23_RXP"
$PN"AL27"35;
"G3_RXP6||SATA26_RXP"
$PN"AL30"36;
"G3_RXP15||SATA37_RXP"
$PN"AP36"37;
"G3_TXN5||SATA25_TXN"
$PN"N27"103;
"G3_TXN11||SATA33_TXN"
$PN"N33"81;
"G3_TXN14||SATA36_TXN"
$PN"T36"82;
"G3_RXP0||SATA20_RXP"
$PN"AL24"38;
"G3_RXP12||SATA34_RXP"
$PN"AK36"39;
"G3_TXN2||SATA22_TXN"
$PN"W24"104;
"G3_RXN5||SATA25_RXN"
$PN"AN26"40;
"G3_TXP10||SATA32_TXP"
$PN"R32"87;
"G3_TXP13||SATA35_TXP"
$PN"P35"77;
%"TAP"
"6","(-3075,5800)","2","mstr_standard","I198";
;
BOM_COST"IO_SLOT"
CDS_LIB"mstr_standard"
ROOM"RISER1"
BODY_TYPE"PLUMBING"
HDL_TAP"TRUE";
"B \NAC \NWC"2;
"S \NAC"
BN"15"119;
%"TAP"
"6","(-3075,5700)","2","mstr_standard","I199";
;
BOM_COST"IO_SLOT"
CDS_LIB"mstr_standard"
ROOM"RISER1"
BODY_TYPE"PLUMBING"
HDL_TAP"TRUE";
"B \NAC \NWC"2;
"S \NAC"
BN"14"120;
%"TAP"
"6","(-3075,5400)","2","standard","I202";
;
BOM_COST"IO_SLOT"
CDS_LIB"standard"
ROOM"RISER1"
BODY_TYPE"PLUMBING"
HDL_TAP"TRUE";
"B \NAC \NWC"2;
"S \NAC"
BN"11"116;
%"TAP"
"6","(-3075,5600)","2","standard","I203";
;
BOM_COST"IO_SLOT"
CDS_LIB"standard"
ROOM"RISER1"
BODY_TYPE"PLUMBING"
HDL_TAP"TRUE";
"B \NAC \NWC"2;
"S \NAC"
BN"13"118;
%"TAP"
"6","(-3075,5500)","2","standard","I204";
;
BOM_COST"IO_SLOT"
CDS_LIB"standard"
ROOM"RISER1"
BODY_TYPE"PLUMBING"
HDL_TAP"TRUE";
"B \NAC \NWC"2;
"S \NAC"
BN"12"117;
%"TAP"
"6","(-3075,5200)","2","standard","I208";
;
BOM_COST"IO_SLOT"
CDS_LIB"standard"
ROOM"RISER1"
BODY_TYPE"PLUMBING"
HDL_TAP"TRUE";
"B \NAC \NWC"2;
"S \NAC"
BN"9"114;
%"TAP"
"6","(-3075,5300)","2","standard","I209";
;
BOM_COST"IO_SLOT"
CDS_LIB"standard"
ROOM"RISER1"
BODY_TYPE"PLUMBING"
HDL_TAP"TRUE";
"B \NAC \NWC"2;
"S \NAC"
BN"10"115;
%"TAP"
"6","(-3075,5100)","2","standard","I212";
;
BOM_COST"IO_SLOT"
CDS_LIB"standard"
ROOM"RISER1"
BODY_TYPE"PLUMBING"
HDL_TAP"TRUE";
"B \NAC \NWC"2;
"S \NAC"
BN"8"109;
%"TAP"
"6","(-3075,5000)","2","standard","I213";
;
BOM_COST"IO_SLOT"
CDS_LIB"standard"
ROOM"RISER1"
BODY_TYPE"PLUMBING"
HDL_TAP"TRUE";
"B \NAC \NWC"2;
"S \NAC"
BN"7"113;
%"TAP"
"6","(-3075,4900)","2","standard","I214";
;
BOM_COST"IO_SLOT"
CDS_LIB"standard"
ROOM"RISER1"
BODY_TYPE"PLUMBING"
HDL_TAP"TRUE";
"B \NAC \NWC"2;
"S \NAC"
BN"6"111;
%"TAP"
"6","(-3075,4700)","2","standard","I218";
;
BOM_COST"IO_SLOT"
CDS_LIB"standard"
ROOM"RISER1"
BODY_TYPE"PLUMBING"
HDL_TAP"TRUE";
"B \NAC \NWC"2;
"S \NAC"
BN"4"110;
%"TAP"
"6","(-3075,4800)","2","standard","I219";
;
BOM_COST"IO_SLOT"
CDS_LIB"standard"
ROOM"RISER1"
BODY_TYPE"PLUMBING"
HDL_TAP"TRUE";
"B \NAC \NWC"2;
"S \NAC"
BN"5"112;
%"TAP"
"6","(-3075,4600)","2","standard","I222";
;
BOM_COST"IO_SLOT"
CDS_LIB"standard"
ROOM"RISER1"
BODY_TYPE"PLUMBING"
HDL_TAP"TRUE";
"B \NAC \NWC"2;
"S \NAC"
BN"3"108;
%"TAP"
"6","(-3075,4500)","2","standard","I223";
;
BOM_COST"IO_SLOT"
CDS_LIB"standard"
ROOM"RISER1"
BODY_TYPE"PLUMBING"
HDL_TAP"TRUE";
"B \NAC \NWC"2;
"S \NAC"
BN"2"106;
%"TAP"
"6","(-3075,4400)","2","standard","I224";
;
BOM_COST"IO_SLOT"
CDS_LIB"standard"
ROOM"RISER1"
BODY_TYPE"PLUMBING"
HDL_TAP"TRUE";
"B \NAC \NWC"2;
"S \NAC"
BN"1"107;
%"TAP"
"6","(-3075,4300)","2","standard","I225";
;
BOM_COST"IO_SLOT"
CDS_LIB"standard"
ROOM"RISER1"
BODY_TYPE"PLUMBING"
HDL_TAP"TRUE";
"B \NAC \NWC"2;
"S \NAC"
BN"0"105;
%"TAP"
"6","(-3050,3125)","2","mstr_standard","I241";
;
CDS_LIB"mstr_standard"
BOM_COST"IO_SLOT"
ROOM"RISER1"
BODY_TYPE"PLUMBING"
HDL_TAP"TRUE";
"B \NAC \NWC"4;
"S \NAC"
BN"15"93;
%"TAP"
"6","(-3050,2925)","2","standard","I242";
;
CDS_LIB"standard"
BOM_COST"IO_SLOT"
ROOM"RISER1"
BODY_TYPE"PLUMBING"
HDL_TAP"TRUE";
"B \NAC \NWC"4;
"S \NAC"
BN"13"89;
%"TAP"
"6","(-3050,2825)","2","standard","I243";
;
CDS_LIB"standard"
BOM_COST"IO_SLOT"
ROOM"RISER1"
BODY_TYPE"PLUMBING"
HDL_TAP"TRUE";
"B \NAC \NWC"4;
"S \NAC"
BN"12"92;
%"TAP"
"6","(-3050,3025)","2","mstr_standard","I244";
;
CDS_LIB"mstr_standard"
BOM_COST"IO_SLOT"
ROOM"RISER1"
BODY_TYPE"PLUMBING"
HDL_TAP"TRUE";
"B \NAC \NWC"4;
"S \NAC"
BN"14"90;
%"TAP"
"6","(-3050,2725)","2","standard","I245";
;
CDS_LIB"standard"
BOM_COST"IO_SLOT"
ROOM"RISER1"
BODY_TYPE"PLUMBING"
HDL_TAP"TRUE";
"B \NAC \NWC"4;
"S \NAC"
BN"11"91;
%"TAP"
"6","(-3050,2625)","2","standard","I246";
;
CDS_LIB"standard"
BOM_COST"IO_SLOT"
ROOM"RISER1"
BODY_TYPE"PLUMBING"
HDL_TAP"TRUE";
"B \NAC \NWC"4;
"S \NAC"
BN"10"88;
%"TAP"
"6","(-3050,2425)","2","standard","I247";
;
CDS_LIB"standard"
BOM_COST"IO_SLOT"
ROOM"RISER1"
BODY_TYPE"PLUMBING"
HDL_TAP"TRUE";
"B \NAC \NWC"4;
"S \NAC"
BN"8"84;
%"TAP"
"6","(-3050,2525)","2","standard","I248";
;
CDS_LIB"standard"
BOM_COST"IO_SLOT"
ROOM"RISER1"
BODY_TYPE"PLUMBING"
HDL_TAP"TRUE";
"B \NAC \NWC"4;
"S \NAC"
BN"9"86;
%"TAP"
"6","(-3050,2325)","2","standard","I249";
;
CDS_LIB"standard"
BOM_COST"IO_SLOT"
ROOM"RISER1"
BODY_TYPE"PLUMBING"
HDL_TAP"TRUE";
"B \NAC \NWC"4;
"S \NAC"
BN"7"85;
%"TAP"
"6","(-3050,2225)","2","standard","I250";
;
CDS_LIB"standard"
BOM_COST"IO_SLOT"
ROOM"RISER1"
BODY_TYPE"PLUMBING"
HDL_TAP"TRUE";
"B \NAC \NWC"4;
"S \NAC"
BN"6"83;
%"TAP"
"6","(-3050,2125)","2","standard","I251";
;
CDS_LIB"standard"
BOM_COST"IO_SLOT"
ROOM"RISER1"
BODY_TYPE"PLUMBING"
HDL_TAP"TRUE";
"B \NAC \NWC"4;
"S \NAC"
BN"5"87;
%"TAP"
"6","(-3050,1825)","2","standard","I257";
;
CDS_LIB"standard"
BOM_COST"IO_SLOT"
ROOM"RISER1"
BODY_TYPE"PLUMBING"
HDL_TAP"TRUE";
"B \NAC \NWC"4;
"S \NAC"
BN"2"77;
%"TAP"
"6","(-3050,2025)","2","standard","I258";
;
CDS_LIB"standard"
BOM_COST"IO_SLOT"
ROOM"RISER1"
BODY_TYPE"PLUMBING"
HDL_TAP"TRUE";
"B \NAC \NWC"4;
"S \NAC"
BN"4"76;
%"TAP"
"6","(-3050,1925)","2","standard","I259";
;
CDS_LIB"standard"
BOM_COST"IO_SLOT"
ROOM"RISER1"
BODY_TYPE"PLUMBING"
HDL_TAP"TRUE";
"B \NAC \NWC"4;
"S \NAC"
BN"3"74;
%"TAP"
"6","(-3050,1725)","2","standard","I260";
;
CDS_LIB"standard"
BOM_COST"IO_SLOT"
ROOM"RISER1"
BODY_TYPE"PLUMBING"
HDL_TAP"TRUE";
"B \NAC \NWC"4;
"S \NAC"
BN"1"75;
%"TAP"
"6","(-3050,1625)","2","standard","I261";
;
CDS_LIB"standard"
BOM_COST"IO_SLOT"
ROOM"RISER1"
BODY_TYPE"PLUMBING"
HDL_TAP"TRUE";
"B \NAC \NWC"4;
"S \NAC"
BN"0"73;
%"TAP"
"6","(-6500,5800)","0","mstr_standard","I262";
;
CDS_LIB"mstr_standard"
BODY_TYPE"PLUMBING"
HDL_TAP"TRUE";
"B \NAC \NWC"5;
"S \NAC"
BN"15"56;
%"TAP"
"6","(-6500,5700)","0","mstr_standard","I263";
;
CDS_LIB"mstr_standard"
BODY_TYPE"PLUMBING"
HDL_TAP"TRUE";
"B \NAC \NWC"5;
"S \NAC"
BN"14"55;
%"TAP"
"6","(-6500,5600)","0","mstr_standard","I266";
;
CDS_LIB"mstr_standard"
BODY_TYPE"PLUMBING"
HDL_TAP"TRUE";
"B \NAC \NWC"5;
"S \NAC"
BN"13"54;
%"TAP"
"6","(-6500,5500)","0","standard","I267";
;
CDS_LIB"standard"
BODY_TYPE"PLUMBING"
HDL_TAP"TRUE";
"B \NAC \NWC"5;
"S \NAC"
BN"12"52;
%"TAP"
"6","(-6500,5400)","0","standard","I268";
;
CDS_LIB"standard"
BODY_TYPE"PLUMBING"
HDL_TAP"TRUE";
"B \NAC \NWC"5;
"S \NAC"
BN"11"50;
%"TAP"
"6","(-6500,5300)","0","standard","I271";
;
CDS_LIB"standard"
BODY_TYPE"PLUMBING"
HDL_TAP"TRUE";
"B \NAC \NWC"5;
"S \NAC"
BN"10"48;
%"TAP"
"6","(-6500,5200)","0","standard","I272";
;
CDS_LIB"standard"
BODY_TYPE"PLUMBING"
HDL_TAP"TRUE";
"B \NAC \NWC"5;
"S \NAC"
BN"9"46;
%"TAP"
"6","(-6500,5100)","0","standard","I276";
;
CDS_LIB"standard"
BODY_TYPE"PLUMBING"
HDL_TAP"TRUE";
"B \NAC \NWC"5;
"S \NAC"
BN"8"44;
%"TAP"
"6","(-6500,4900)","0","standard","I277";
;
CDS_LIB"standard"
BODY_TYPE"PLUMBING"
HDL_TAP"TRUE";
"B \NAC \NWC"5;
"S \NAC"
BN"6"64;
%"TAP"
"6","(-6500,5000)","0","standard","I278";
;
CDS_LIB"standard"
BODY_TYPE"PLUMBING"
HDL_TAP"TRUE";
"B \NAC \NWC"5;
"S \NAC"
BN"7"72;
%"TAP"
"6","(-6500,4800)","0","standard","I281";
;
CDS_LIB"standard"
BODY_TYPE"PLUMBING"
HDL_TAP"TRUE";
"B \NAC \NWC"5;
"S \NAC"
BN"5"70;
%"TAP"
"6","(-6500,4700)","0","standard","I282";
;
CDS_LIB"standard"
BODY_TYPE"PLUMBING"
HDL_TAP"TRUE";
"B \NAC \NWC"5;
"S \NAC"
BN"4"62;
%"TAP"
"6","(-6500,4600)","0","standard","I286";
;
CDS_LIB"standard"
BODY_TYPE"PLUMBING"
HDL_TAP"TRUE";
"B \NAC \NWC"5;
"S \NAC"
BN"3"68;
%"TAP"
"6","(-6500,4400)","0","standard","I287";
;
CDS_LIB"standard"
BODY_TYPE"PLUMBING"
HDL_TAP"TRUE";
"B \NAC \NWC"5;
"S \NAC"
BN"1"66;
%"TAP"
"6","(-6500,4500)","0","standard","I288";
;
CDS_LIB"standard"
BODY_TYPE"PLUMBING"
HDL_TAP"TRUE";
"B \NAC \NWC"5;
"S \NAC"
BN"2"60;
%"TAP"
"6","(-6500,4300)","0","standard","I291";
;
CDS_LIB"standard"
BODY_TYPE"PLUMBING"
HDL_TAP"TRUE";
"B \NAC \NWC"5;
"S \NAC"
BN"0"58;
%"TAP"
"6","(-6475,3125)","0","standard","I296";
;
CDS_LIB"standard"
BODY_TYPE"PLUMBING"
HDL_TAP"TRUE";
"B \NAC \NWC"8;
"S \NAC"
BN"15"38;
%"TAP"
"6","(-6475,2925)","0","standard","I298";
;
CDS_LIB"standard"
BODY_TYPE"PLUMBING"
HDL_TAP"TRUE";
"B \NAC \NWC"8;
"S \NAC"
BN"13"13;
%"TAP"
"6","(-6475,3025)","0","standard","I299";
;
CDS_LIB"standard"
BODY_TYPE"PLUMBING"
HDL_TAP"TRUE";
"B \NAC \NWC"8;
"S \NAC"
BN"14"25;
%"TAP"
"6","(-6475,2825)","0","standard","I300";
;
CDS_LIB"standard"
BODY_TYPE"PLUMBING"
HDL_TAP"TRUE";
"B \NAC \NWC"8;
"S \NAC"
BN"12"35;
%"TAP"
"6","(-6475,2725)","0","standard","I303";
;
CDS_LIB"standard"
BODY_TYPE"PLUMBING"
HDL_TAP"TRUE";
"B \NAC \NWC"8;
"S \NAC"
BN"11"26;
%"TAP"
"6","(-6475,2625)","0","standard","I304";
;
CDS_LIB"standard"
BODY_TYPE"PLUMBING"
HDL_TAP"TRUE";
"B \NAC \NWC"8;
"S \NAC"
BN"10"14;
%"TAP"
"6","(-6475,2425)","0","standard","I308";
;
CDS_LIB"standard"
BODY_TYPE"PLUMBING"
HDL_TAP"TRUE";
"B \NAC \NWC"8;
"S \NAC"
BN"8"23;
%"TAP"
"6","(-6475,2525)","0","standard","I309";
;
CDS_LIB"standard"
BODY_TYPE"PLUMBING"
HDL_TAP"TRUE";
"B \NAC \NWC"8;
"S \NAC"
BN"9"36;
%"TAP"
"6","(-6475,2325)","0","standard","I310";
;
CDS_LIB"standard"
BODY_TYPE"PLUMBING"
HDL_TAP"TRUE";
"B \NAC \NWC"8;
"S \NAC"
BN"7"32;
%"TAP"
"6","(-6475,2225)","0","standard","I313";
;
CDS_LIB"standard"
BODY_TYPE"PLUMBING"
HDL_TAP"TRUE";
"B \NAC \NWC"8;
"S \NAC"
BN"6"20;
%"TAP"
"6","(-6475,2125)","0","standard","I314";
;
CDS_LIB"standard"
BODY_TYPE"PLUMBING"
HDL_TAP"TRUE";
"B \NAC \NWC"8;
"S \NAC"
BN"5"27;
%"TAP"
"6","(-6475,2025)","0","standard","I320";
;
CDS_LIB"standard"
BODY_TYPE"PLUMBING"
HDL_TAP"TRUE";
"B \NAC \NWC"8;
"S \NAC"
BN"4"16;
%"TAP"
"6","(-6475,1925)","0","standard","I321";
;
CDS_LIB"standard"
BODY_TYPE"PLUMBING"
HDL_TAP"TRUE";
"B \NAC \NWC"8;
"S \NAC"
BN"3"39;
%"TAP"
"6","(-6475,1825)","0","standard","I322";
;
CDS_LIB"standard"
BODY_TYPE"PLUMBING"
HDL_TAP"TRUE";
"B \NAC \NWC"8;
"S \NAC"
BN"2"28;
%"TAP"
"6","(-6475,1725)","0","standard","I325";
;
CDS_LIB"standard"
BODY_TYPE"PLUMBING"
HDL_TAP"TRUE";
"B \NAC \NWC"8;
"S \NAC"
BN"1"15;
%"TAP"
"6","(-6475,1625)","0","standard","I327";
;
CDS_LIB"standard"
BODY_TYPE"PLUMBING"
HDL_TAP"TRUE";
"B \NAC \NWC"8;
"S \NAC"
BN"0"37;
%"TAP"
"6","(-6650,5750)","0","mstr_standard","I398";
;
CDS_LIB"mstr_standard"
BODY_TYPE"PLUMBING"
HDL_TAP"TRUE";
"B \NAC \NWC"6;
"S \NAC"
BN"15"53;
%"TAP"
"6","(-6650,5650)","0","mstr_standard","I399";
;
CDS_LIB"mstr_standard"
BODY_TYPE"PLUMBING"
HDL_TAP"TRUE";
"B \NAC \NWC"6;
"S \NAC"
BN"14"51;
%"TAP"
"6","(-6650,5450)","0","standard","I400";
;
CDS_LIB"standard"
BODY_TYPE"PLUMBING"
HDL_TAP"TRUE";
"B \NAC \NWC"6;
"S \NAC"
BN"12"47;
%"TAP"
"6","(-6650,5550)","0","standard","I401";
;
CDS_LIB"standard"
BODY_TYPE"PLUMBING"
HDL_TAP"TRUE";
"B \NAC \NWC"6;
"S \NAC"
BN"13"49;
%"TAP"
"6","(-6650,5150)","0","standard","I402";
;
CDS_LIB"standard"
BODY_TYPE"PLUMBING"
HDL_TAP"TRUE";
"B \NAC \NWC"6;
"S \NAC"
BN"9"42;
%"TAP"
"6","(-6650,5350)","0","standard","I403";
;
CDS_LIB"standard"
BODY_TYPE"PLUMBING"
HDL_TAP"TRUE";
"B \NAC \NWC"6;
"S \NAC"
BN"11"45;
%"TAP"
"6","(-6650,5250)","0","standard","I404";
;
CDS_LIB"standard"
BODY_TYPE"PLUMBING"
HDL_TAP"TRUE";
"B \NAC \NWC"6;
"S \NAC"
BN"10"43;
%"TAP"
"6","(-6650,4950)","0","standard","I405";
;
CDS_LIB"standard"
BODY_TYPE"PLUMBING"
HDL_TAP"TRUE";
"B \NAC \NWC"6;
"S \NAC"
BN"7"71;
%"TAP"
"6","(-6650,5050)","0","standard","I406";
;
CDS_LIB"standard"
BODY_TYPE"PLUMBING"
HDL_TAP"TRUE";
"B \NAC \NWC"6;
"S \NAC"
BN"8"41;
%"TAP"
"6","(-6650,4850)","0","standard","I407";
;
CDS_LIB"standard"
BODY_TYPE"PLUMBING"
HDL_TAP"TRUE";
"B \NAC \NWC"6;
"S \NAC"
BN"6"63;
%"TAP"
"6","(-6650,4650)","0","standard","I408";
;
CDS_LIB"standard"
BODY_TYPE"PLUMBING"
HDL_TAP"TRUE";
"B \NAC \NWC"6;
"S \NAC"
BN"4"61;
%"TAP"
"6","(-6650,4750)","0","standard","I409";
;
CDS_LIB"standard"
BODY_TYPE"PLUMBING"
HDL_TAP"TRUE";
"B \NAC \NWC"6;
"S \NAC"
BN"5"69;
%"TAP"
"6","(-6650,4450)","0","standard","I410";
;
CDS_LIB"standard"
BODY_TYPE"PLUMBING"
HDL_TAP"TRUE";
"B \NAC \NWC"6;
"S \NAC"
BN"2"59;
%"TAP"
"6","(-6650,4550)","0","standard","I411";
;
CDS_LIB"standard"
BODY_TYPE"PLUMBING"
HDL_TAP"TRUE";
"B \NAC \NWC"6;
"S \NAC"
BN"3"67;
%"TAP"
"6","(-6650,4350)","0","standard","I412";
;
CDS_LIB"standard"
BODY_TYPE"PLUMBING"
HDL_TAP"TRUE";
"B \NAC \NWC"6;
"S \NAC"
BN"1"65;
%"TAP"
"6","(-6650,4250)","0","standard","I413";
;
CDS_LIB"standard"
BODY_TYPE"PLUMBING"
HDL_TAP"TRUE";
"B \NAC \NWC"6;
"S \NAC"
BN"0"57;
%"TAP"
"6","(-2925,5750)","2","mstr_standard","I416";
;
CDS_LIB"mstr_standard"
BOM_COST"IO_SLOT"
ROOM"RISER1"
BODY_TYPE"PLUMBING"
HDL_TAP"TRUE";
"B \NAC \NWC"1;
"S \NAC"
BN"15"128;
%"TAP"
"6","(-2925,5650)","2","mstr_standard","I417";
;
BOM_COST"IO_SLOT"
CDS_LIB"mstr_standard"
ROOM"RISER1"
BODY_TYPE"PLUMBING"
HDL_TAP"TRUE";
"B \NAC \NWC"1;
"S \NAC"
BN"14"127;
%"TAP"
"6","(-2925,5250)","2","standard","I418";
;
BOM_COST"IO_SLOT"
CDS_LIB"standard"
ROOM"RISER1"
BODY_TYPE"PLUMBING"
HDL_TAP"TRUE";
"B \NAC \NWC"1;
"S \NAC"
BN"10"123;
%"TAP"
"6","(-2925,5150)","2","standard","I419";
;
BOM_COST"IO_SLOT"
CDS_LIB"standard"
ROOM"RISER1"
BODY_TYPE"PLUMBING"
HDL_TAP"TRUE";
"B \NAC \NWC"1;
"S \NAC"
BN"9"122;
%"TAP"
"6","(-2925,5350)","2","standard","I420";
;
BOM_COST"IO_SLOT"
CDS_LIB"standard"
ROOM"RISER1"
BODY_TYPE"PLUMBING"
HDL_TAP"TRUE";
"B \NAC \NWC"1;
"S \NAC"
BN"11"124;
%"TAP"
"6","(-2925,5450)","2","standard","I421";
;
BOM_COST"IO_SLOT"
CDS_LIB"standard"
ROOM"RISER1"
BODY_TYPE"PLUMBING"
HDL_TAP"TRUE";
"B \NAC \NWC"1;
"S \NAC"
BN"12"125;
%"TAP"
"6","(-2925,5550)","2","standard","I422";
;
BOM_COST"IO_SLOT"
CDS_LIB"standard"
ROOM"RISER1"
BODY_TYPE"PLUMBING"
HDL_TAP"TRUE";
"B \NAC \NWC"1;
"S \NAC"
BN"13"126;
%"TAP"
"6","(-2925,4850)","2","standard","I423";
;
BOM_COST"IO_SLOT"
CDS_LIB"standard"
ROOM"RISER1"
BODY_TYPE"PLUMBING"
HDL_TAP"TRUE";
"B \NAC \NWC"1;
"S \NAC"
BN"6"132;
%"TAP"
"6","(-2925,4650)","2","standard","I424";
;
BOM_COST"IO_SLOT"
CDS_LIB"standard"
ROOM"RISER1"
BODY_TYPE"PLUMBING"
HDL_TAP"TRUE";
"B \NAC \NWC"1;
"S \NAC"
BN"4"131;
%"TAP"
"6","(-2925,4750)","2","standard","I425";
;
BOM_COST"IO_SLOT"
CDS_LIB"standard"
ROOM"RISER1"
BODY_TYPE"PLUMBING"
HDL_TAP"TRUE";
"B \NAC \NWC"1;
"S \NAC"
BN"5"135;
%"TAP"
"6","(-2925,5050)","2","standard","I426";
;
BOM_COST"IO_SLOT"
CDS_LIB"standard"
ROOM"RISER1"
BODY_TYPE"PLUMBING"
HDL_TAP"TRUE";
"B \NAC \NWC"1;
"S \NAC"
BN"8"121;
%"TAP"
"6","(-2925,4950)","2","standard","I427";
;
BOM_COST"IO_SLOT"
CDS_LIB"standard"
ROOM"RISER1"
BODY_TYPE"PLUMBING"
HDL_TAP"TRUE";
"B \NAC \NWC"1;
"S \NAC"
BN"7"136;
%"TAP"
"6","(-2925,4250)","2","standard","I428";
;
BOM_COST"IO_SLOT"
CDS_LIB"standard"
ROOM"RISER1"
BODY_TYPE"PLUMBING"
HDL_TAP"TRUE";
"B \NAC \NWC"1;
"S \NAC"
BN"0"129;
%"TAP"
"6","(-2925,4550)","2","standard","I429";
;
BOM_COST"IO_SLOT"
CDS_LIB"standard"
ROOM"RISER1"
BODY_TYPE"PLUMBING"
HDL_TAP"TRUE";
"B \NAC \NWC"1;
"S \NAC"
BN"3"134;
%"TAP"
"6","(-2925,4450)","2","standard","I430";
;
BOM_COST"IO_SLOT"
CDS_LIB"standard"
ROOM"RISER1"
BODY_TYPE"PLUMBING"
HDL_TAP"TRUE";
"B \NAC \NWC"1;
"S \NAC"
BN"2"130;
%"TAP"
"6","(-2925,4350)","2","standard","I431";
;
CDS_LIB"standard"
BOM_COST"IO_SLOT"
ROOM"RISER1"
BODY_TYPE"PLUMBING"
HDL_TAP"TRUE";
"B \NAC \NWC"1;
"S \NAC"
BN"1"133;
%"TAP"
"6","(-2900,3075)","2","mstr_standard","I433";
;
BOM_COST"IO_SLOT"
CDS_LIB"mstr_standard"
ROOM"RISER1"
BODY_TYPE"PLUMBING"
HDL_TAP"TRUE";
"B \NAC \NWC"3;
"S \NAC"
BN"15"102;
%"TAP"
"6","(-2900,2975)","2","mstr_standard","I434";
;
CDS_LIB"mstr_standard"
BOM_COST"IO_SLOT"
ROOM"RISER1"
BODY_TYPE"PLUMBING"
HDL_TAP"TRUE";
"B \NAC \NWC"3;
"S \NAC"
BN"14"98;
%"TAP"
"6","(-2900,2875)","2","standard","I435";
;
CDS_LIB"standard"
BOM_COST"IO_SLOT"
ROOM"RISER1"
BODY_TYPE"PLUMBING"
HDL_TAP"TRUE";
"B \NAC \NWC"3;
"S \NAC"
BN"13"104;
%"TAP"
"6","(-2900,2775)","2","standard","I436";
;
CDS_LIB"standard"
BOM_COST"IO_SLOT"
ROOM"RISER1"
BODY_TYPE"PLUMBING"
HDL_TAP"TRUE";
"B \NAC \NWC"3;
"S \NAC"
BN"12"100;
%"TAP"
"6","(-2900,2675)","2","standard","I437";
;
CDS_LIB"standard"
BOM_COST"IO_SLOT"
ROOM"RISER1"
BODY_TYPE"PLUMBING"
HDL_TAP"TRUE";
"B \NAC \NWC"3;
"S \NAC"
BN"11"95;
%"TAP"
"6","(-2900,2575)","2","standard","I438";
;
CDS_LIB"standard"
BOM_COST"IO_SLOT"
ROOM"RISER1"
BODY_TYPE"PLUMBING"
HDL_TAP"TRUE";
"B \NAC \NWC"3;
"S \NAC"
BN"10"103;
%"TAP"
"6","(-2900,2475)","2","standard","I439";
;
CDS_LIB"standard"
BOM_COST"IO_SLOT"
ROOM"RISER1"
BODY_TYPE"PLUMBING"
HDL_TAP"TRUE";
"B \NAC \NWC"3;
"S \NAC"
BN"9"101;
%"TAP"
"6","(-2900,2375)","2","standard","I440";
;
CDS_LIB"standard"
BOM_COST"IO_SLOT"
ROOM"RISER1"
BODY_TYPE"PLUMBING"
HDL_TAP"TRUE";
"B \NAC \NWC"3;
"S \NAC"
BN"8"96;
%"TAP"
"6","(-2900,2275)","2","standard","I441";
;
CDS_LIB"standard"
BOM_COST"IO_SLOT"
ROOM"RISER1"
BODY_TYPE"PLUMBING"
HDL_TAP"TRUE";
"B \NAC \NWC"3;
"S \NAC"
BN"7"99;
%"TAP"
"6","(-2900,2175)","2","standard","I442";
;
CDS_LIB"standard"
BOM_COST"IO_SLOT"
ROOM"RISER1"
BODY_TYPE"PLUMBING"
HDL_TAP"TRUE";
"B \NAC \NWC"3;
"S \NAC"
BN"6"94;
%"TAP"
"6","(-2900,2075)","2","standard","I443";
;
CDS_LIB"standard"
BOM_COST"IO_SLOT"
ROOM"RISER1"
BODY_TYPE"PLUMBING"
HDL_TAP"TRUE";
"B \NAC \NWC"3;
"S \NAC"
BN"5"97;
%"TAP"
"6","(-2900,1975)","2","standard","I444";
;
CDS_LIB"standard"
BOM_COST"IO_SLOT"
ROOM"RISER1"
BODY_TYPE"PLUMBING"
HDL_TAP"TRUE";
"B \NAC \NWC"3;
"S \NAC"
BN"4"81;
%"TAP"
"6","(-2900,1875)","2","standard","I445";
;
CDS_LIB"standard"
BOM_COST"IO_SLOT"
ROOM"RISER1"
BODY_TYPE"PLUMBING"
HDL_TAP"TRUE";
"B \NAC \NWC"3;
"S \NAC"
BN"3"79;
%"TAP"
"6","(-2900,1675)","2","standard","I446";
;
BOM_COST"IO_SLOT"
CDS_LIB"standard"
ROOM"RISER1"
BODY_TYPE"PLUMBING"
HDL_TAP"TRUE";
"B \NAC \NWC"3;
"S \NAC"
BN"1"82;
%"TAP"
"6","(-2900,1775)","2","standard","I447";
;
CDS_LIB"standard"
BOM_COST"IO_SLOT"
ROOM"RISER1"
BODY_TYPE"PLUMBING"
HDL_TAP"TRUE";
"B \NAC \NWC"3;
"S \NAC"
BN"2"78;
%"TAP"
"6","(-2900,1575)","2","standard","I448";
;
CDS_LIB"standard"
BOM_COST"IO_SLOT"
ROOM"RISER1"
BODY_TYPE"PLUMBING"
HDL_TAP"TRUE";
"B \NAC \NWC"3;
"S \NAC"
BN"0"80;
%"TAP"
"6","(-6625,3075)","0","mstr_standard","I449";
;
CDS_LIB"mstr_standard"
BODY_TYPE"PLUMBING"
HDL_TAP"TRUE";
"B \NAC \NWC"7;
"S \NAC"
BN"15"30;
%"TAP"
"6","(-6625,2975)","0","mstr_standard","I450";
;
CDS_LIB"mstr_standard"
BODY_TYPE"PLUMBING"
HDL_TAP"TRUE";
"B \NAC \NWC"7;
"S \NAC"
BN"14"17;
%"TAP"
"6","(-6625,2875)","0","standard","I451";
;
CDS_LIB"standard"
BODY_TYPE"PLUMBING"
HDL_TAP"TRUE";
"B \NAC \NWC"7;
"S \NAC"
BN"13"9;
%"TAP"
"6","(-6625,2775)","0","standard","I452";
;
CDS_LIB"standard"
BODY_TYPE"PLUMBING"
HDL_TAP"TRUE";
"B \NAC \NWC"7;
"S \NAC"
BN"12"31;
%"TAP"
"6","(-6625,2675)","0","standard","I453";
;
CDS_LIB"standard"
BODY_TYPE"PLUMBING"
HDL_TAP"TRUE";
"B \NAC \NWC"7;
"S \NAC"
BN"11"18;
%"TAP"
"6","(-6625,2475)","0","standard","I454";
;
CDS_LIB"standard"
BODY_TYPE"PLUMBING"
HDL_TAP"TRUE";
"B \NAC \NWC"7;
"S \NAC"
BN"9"29;
%"TAP"
"6","(-6625,2575)","0","standard","I455";
;
CDS_LIB"standard"
BODY_TYPE"PLUMBING"
HDL_TAP"TRUE";
"B \NAC \NWC"7;
"S \NAC"
BN"10"40;
%"TAP"
"6","(-6625,2375)","0","standard","I456";
;
CDS_LIB"standard"
BODY_TYPE"PLUMBING"
HDL_TAP"TRUE";
"B \NAC \NWC"7;
"S \NAC"
BN"8"19;
%"TAP"
"6","(-6625,2275)","0","standard","I457";
;
CDS_LIB"standard"
BODY_TYPE"PLUMBING"
HDL_TAP"TRUE";
"B \NAC \NWC"7;
"S \NAC"
BN"7"24;
%"TAP"
"6","(-6625,2175)","0","standard","I458";
;
CDS_LIB"standard"
BODY_TYPE"PLUMBING"
HDL_TAP"TRUE";
"B \NAC \NWC"7;
"S \NAC"
BN"6"12;
%"TAP"
"6","(-6625,1975)","0","standard","I459";
;
CDS_LIB"standard"
BODY_TYPE"PLUMBING"
HDL_TAP"TRUE";
"B \NAC \NWC"7;
"S \NAC"
BN"4"21;
%"TAP"
"6","(-6625,2075)","0","standard","I460";
;
CDS_LIB"standard"
BODY_TYPE"PLUMBING"
HDL_TAP"TRUE";
"B \NAC \NWC"7;
"S \NAC"
BN"5"34;
%"TAP"
"6","(-6625,1875)","0","standard","I461";
;
CDS_LIB"standard"
BODY_TYPE"PLUMBING"
HDL_TAP"TRUE";
"B \NAC \NWC"7;
"S \NAC"
BN"3"10;
%"TAP"
"6","(-6625,1775)","0","standard","I462";
;
CDS_LIB"standard"
BODY_TYPE"PLUMBING"
HDL_TAP"TRUE";
"B \NAC \NWC"7;
"S \NAC"
BN"2"33;
%"TAP"
"6","(-6625,1575)","0","standard","I463";
;
CDS_LIB"standard"
BODY_TYPE"PLUMBING"
HDL_TAP"TRUE";
"B \NAC \NWC"7;
"S \NAC"
BN"0"11;
%"TAP"
"6","(-6625,1675)","0","standard","I464";
;
CDS_LIB"standard"
BODY_TYPE"PLUMBING"
HDL_TAP"TRUE";
"B \NAC \NWC"7;
"S \NAC"
BN"1"22;
END.
